(kicad_pcb
	(version 20260206)
	(generator "pcbnew")
	(generator_version "10.0")
	(general
		(thickness 1.6)
		(legacy_teardrops no)
	)
	(paper "A4")
	(title_block
		(title "01162023_DA0F0TEBIF0_F0T_Expander_BD_F_brd_V02_OCP.brd")
		(comment 1 "Grand Teton / footprints 4559-4564 of 9728")
	)
	(layers
		(0 "F.Cu" signal "TOP")
		(4 "In1.Cu" signal "GND")
		(6 "In2.Cu" signal "VCC")
		(8 "In3.Cu" signal "VCC1")
		(10 "In4.Cu" signal "GND1")
		(12 "In5.Cu" signal "IN1")
		(14 "In6.Cu" signal "GND2")
		(16 "In7.Cu" signal "IN2")
		(18 "In8.Cu" signal "GND3")
		(20 "In9.Cu" signal "IN3")
		(22 "In10.Cu" signal "GND4")
		(24 "In11.Cu" signal "IN4")
		(26 "In12.Cu" signal "GND5")
		(28 "In13.Cu" signal "IN5")
		(30 "In14.Cu" signal "GND6")
		(32 "In15.Cu" signal "IN6")
		(34 "In16.Cu" signal "GND7")
		(2 "B.Cu" signal "BOTTOM")
		(9 "F.Adhes" user "F.Adhesive")
		(11 "B.Adhes" user "B.Adhesive")
		(13 "F.Paste" user "Package Geometry/Pastemask Top")
		(15 "B.Paste" user "Package Geometry/Pastemask Bottom")
		(5 "F.SilkS" user "Ref Des/Silkscreen Top")
		(7 "B.SilkS" user "Ref Des/Silkscreen Bottom")
		(1 "F.Mask" user "Board Geometry/Soldermask Top")
		(3 "B.Mask" user "Board Geometry/Soldermask Bottom")
		(17 "Dwgs.User" user "User.Drawings")
		(19 "Cmts.User" user "User.Comments")
		(21 "Eco1.User" user "User.Eco1")
		(23 "Eco2.User" user "User.Eco2")
		(25 "Edge.Cuts" user "Board Geometry/Outline")
		(27 "Margin" user)
		(31 "F.CrtYd" user "Package Geometry/Place Bound Top")
		(29 "B.CrtYd" user "Package Geometry/Place Bound Bottom")
		(35 "F.Fab" user "Ref Des/Assembly Top")
		(33 "B.Fab" user "Ref Des/Assembly Bottom")
	)
	(footprint ""
		(layer "F.Cu")
		(at 238.909098 -27.04973 180)
		(property "Reference" "C2771"
			(at 0 0 180)
			(layer "F.SilkS")
			(hide yes)
			(effects
				(font
					(size 1.27 1.27)
				)
			)
		)
		(property "Value" ""
			(at 0 0 180)
			(layer "F.Fab")
			(effects
				(font
					(size 1.27 1.27)
				)
			)
		)
		(duplicate_pad_numbers_are_jumpers no)
		(fp_line
			(start 0.7874 0.4064)
			(end -0.7874 0.4064)
			(stroke
				(width 0.1524)
				(type default)
			)
			(layer "F.SilkS")
		)
		(fp_line
			(start 0.7874 -0.4064)
			(end 0.7874 0.4064)
			(stroke
				(width 0.1524)
				(type default)
			)
			(layer "F.SilkS")
		)
		(fp_line
			(start -0.7874 0.4064)
			(end -0.7874 -0.4064)
			(stroke
				(width 0.1524)
				(type default)
			)
			(layer "F.SilkS")
		)
		(fp_line
			(start -0.7874 -0.4064)
			(end 0.7874 -0.4064)
			(stroke
				(width 0.1524)
				(type default)
			)
			(layer "F.SilkS")
		)
		(fp_line
			(start 0.67945 0.3048)
			(end 0.120396 0.3048)
			(stroke
				(width 0.1)
				(type default)
			)
			(layer "F.Fab")
		)
		(fp_line
			(start 0.67945 -0.3048)
			(end 0.67945 0.3048)
			(stroke
				(width 0.1)
				(type default)
			)
			(layer "F.Fab")
		)
		(fp_line
			(start 0.12065 -0.2794)
			(end 0.12065 -0.3048)
			(stroke
				(width 0.1)
				(type default)
			)
			(layer "F.Fab")
		)
		(fp_line
			(start 0.12065 -0.3048)
			(end 0.67945 -0.3048)
			(stroke
				(width 0.1)
				(type default)
			)
			(layer "F.Fab")
		)
		(fp_line
			(start 0.120396 0.3048)
			(end 0.120396 0.2794)
			(stroke
				(width 0.1)
				(type default)
			)
			(layer "F.Fab")
		)
		(fp_line
			(start 0.120396 0.2794)
			(end -0.12065 0.2794)
			(stroke
				(width 0.1)
				(type default)
			)
			(layer "F.Fab")
		)
		(fp_line
			(start -0.12065 0.3048)
			(end -0.67945 0.3048)
			(stroke
				(width 0.1)
				(type default)
			)
			(layer "F.Fab")
		)
		(fp_line
			(start -0.12065 0.2794)
			(end -0.12065 0.3048)
			(stroke
				(width 0.1)
				(type default)
			)
			(layer "F.Fab")
		)
		(fp_line
			(start -0.12065 -0.2794)
			(end 0.12065 -0.2794)
			(stroke
				(width 0.1)
				(type default)
			)
			(layer "F.Fab")
		)
		(fp_line
			(start -0.12065 -0.305054)
			(end -0.12065 -0.2794)
			(stroke
				(width 0.1)
				(type default)
			)
			(layer "F.Fab")
		)
		(fp_line
			(start -0.67945 0.3048)
			(end -0.67945 -0.305054)
			(stroke
				(width 0.1)
				(type default)
			)
			(layer "F.Fab")
		)
		(fp_line
			(start -0.67945 -0.305054)
			(end -0.12065 -0.305054)
			(stroke
				(width 0.1)
				(type default)
			)
			(layer "F.Fab")
		)
		(pad "1" smd circle
			(at -0.40005 0 180)
			(size 0 0)
			(layers "F.Cu" "F.Mask" "F.Paste")
			(net "PRSNT_SSD8_R_N")
		)
		(pad "2" smd circle
			(at 0.40005 0 180)
			(size 0 0)
			(layers "F.Cu" "F.Mask" "F.Paste")
			(net "GND")
		)
	)
	(footprint ""
		(layer "F.Cu")
		(at 430.183544 -61.487812 180)
		(property "Reference" "R6025"
			(at 0 0 180)
			(layer "F.SilkS")
			(hide yes)
			(effects
				(font
					(size 1.27 1.27)
				)
			)
		)
		(property "Value" ""
			(at 0 0 180)
			(layer "F.Fab")
			(effects
				(font
					(size 1.27 1.27)
				)
			)
		)
		(duplicate_pad_numbers_are_jumpers no)
		(fp_line
			(start 0.7874 0.4064)
			(end -0.7874 0.4064)
			(stroke
				(width 0.1524)
				(type default)
			)
			(layer "F.SilkS")
		)
		(fp_line
			(start 0.7874 -0.4064)
			(end 0.7874 0.4064)
			(stroke
				(width 0.1524)
				(type default)
			)
			(layer "F.SilkS")
		)
		(fp_line
			(start -0.7874 0.4064)
			(end -0.7874 -0.4064)
			(stroke
				(width 0.1524)
				(type default)
			)
			(layer "F.SilkS")
		)
		(fp_line
			(start -0.7874 -0.4064)
			(end 0.7874 -0.4064)
			(stroke
				(width 0.1524)
				(type default)
			)
			(layer "F.SilkS")
		)
		(fp_line
			(start 0.67945 0.3048)
			(end 0.120396 0.3048)
			(stroke
				(width 0.1)
				(type default)
			)
			(layer "F.Fab")
		)
		(fp_line
			(start 0.67945 -0.3048)
			(end 0.67945 0.3048)
			(stroke
				(width 0.1)
				(type default)
			)
			(layer "F.Fab")
		)
		(fp_line
			(start 0.12065 -0.2794)
			(end 0.12065 -0.3048)
			(stroke
				(width 0.1)
				(type default)
			)
			(layer "F.Fab")
		)
		(fp_line
			(start 0.12065 -0.3048)
			(end 0.67945 -0.3048)
			(stroke
				(width 0.1)
				(type default)
			)
			(layer "F.Fab")
		)
		(fp_line
			(start 0.120396 0.3048)
			(end 0.120396 0.2794)
			(stroke
				(width 0.1)
				(type default)
			)
			(layer "F.Fab")
		)
		(fp_line
			(start 0.120396 0.2794)
			(end -0.12065 0.2794)
			(stroke
				(width 0.1)
				(type default)
			)
			(layer "F.Fab")
		)
		(fp_line
			(start -0.12065 0.3048)
			(end -0.67945 0.3048)
			(stroke
				(width 0.1)
				(type default)
			)
			(layer "F.Fab")
		)
		(fp_line
			(start -0.12065 0.2794)
			(end -0.12065 0.3048)
			(stroke
				(width 0.1)
				(type default)
			)
			(layer "F.Fab")
		)
		(fp_line
			(start -0.12065 -0.2794)
			(end 0.12065 -0.2794)
			(stroke
				(width 0.1)
				(type default)
			)
			(layer "F.Fab")
		)
		(fp_line
			(start -0.12065 -0.305054)
			(end -0.12065 -0.2794)
			(stroke
				(width 0.1)
				(type default)
			)
			(layer "F.Fab")
		)
		(fp_line
			(start -0.67945 0.3048)
			(end -0.67945 -0.305054)
			(stroke
				(width 0.1)
				(type default)
			)
			(layer "F.Fab")
		)
		(fp_line
			(start -0.67945 -0.305054)
			(end -0.12065 -0.305054)
			(stroke
				(width 0.1)
				(type default)
			)
			(layer "F.Fab")
		)
		(pad "1" smd circle
			(at -0.40005 0 180)
			(size 0 0)
			(layers "F.Cu" "F.Mask" "F.Paste")
			(net "PWRGD_P12V_SSD15_D")
		)
		(pad "2" smd circle
			(at 0.40005 0 180)
			(size 0 0)
			(layers "F.Cu" "F.Mask" "F.Paste")
			(net "PWRGD_P12V_SSD15_R")
		)
	)
	(footprint ""
		(layer "F.Cu")
		(at 16.85163 -124.120656 -90)
		(property "Reference" "PC452"
			(at 0 0 270)
			(layer "F.SilkS")
			(hide yes)
			(effects
				(font
					(size 1.27 1.27)
				)
			)
		)
		(property "Value" ""
			(at 0 0 270)
			(layer "F.Fab")
			(effects
				(font
					(size 1.27 1.27)
				)
			)
		)
		(duplicate_pad_numbers_are_jumpers no)
		(fp_line
			(start -0.7874 0.4064)
			(end -0.7874 -0.4064)
			(stroke
				(width 0.1524)
				(type default)
			)
			(layer "F.SilkS")
		)
		(fp_line
			(start 0.7874 0.4064)
			(end -0.7874 0.4064)
			(stroke
				(width 0.1524)
				(type default)
			)
			(layer "F.SilkS")
		)
		(fp_line
			(start -0.7874 -0.4064)
			(end 0.7874 -0.4064)
			(stroke
				(width 0.1524)
				(type default)
			)
			(layer "F.SilkS")
		)
		(fp_line
			(start 0.7874 -0.4064)
			(end 0.7874 0.4064)
			(stroke
				(width 0.1524)
				(type default)
			)
			(layer "F.SilkS")
		)
		(fp_line
			(start -0.67945 0.3048)
			(end -0.67945 -0.305054)
			(stroke
				(width 0.1)
				(type default)
			)
			(layer "F.Fab")
		)
		(fp_line
			(start -0.12065 0.3048)
			(end -0.67945 0.3048)
			(stroke
				(width 0.1)
				(type default)
			)
			(layer "F.Fab")
		)
		(fp_line
			(start 0.120396 0.3048)
			(end 0.120396 0.2794)
			(stroke
				(width 0.1)
				(type default)
			)
			(layer "F.Fab")
		)
		(fp_line
			(start 0.67945 0.3048)
			(end 0.120396 0.3048)
			(stroke
				(width 0.1)
				(type default)
			)
			(layer "F.Fab")
		)
		(fp_line
			(start -0.12065 0.2794)
			(end -0.12065 0.3048)
			(stroke
				(width 0.1)
				(type default)
			)
			(layer "F.Fab")
		)
		(fp_line
			(start 0.120396 0.2794)
			(end -0.12065 0.2794)
			(stroke
				(width 0.1)
				(type default)
			)
			(layer "F.Fab")
		)
		(fp_line
			(start -0.12065 -0.2794)
			(end 0.12065 -0.2794)
			(stroke
				(width 0.1)
				(type default)
			)
			(layer "F.Fab")
		)
		(fp_line
			(start 0.12065 -0.2794)
			(end 0.12065 -0.3048)
			(stroke
				(width 0.1)
				(type default)
			)
			(layer "F.Fab")
		)
		(fp_line
			(start 0.12065 -0.3048)
			(end 0.67945 -0.3048)
			(stroke
				(width 0.1)
				(type default)
			)
			(layer "F.Fab")
		)
		(fp_line
			(start 0.67945 -0.3048)
			(end 0.67945 0.3048)
			(stroke
				(width 0.1)
				(type default)
			)
			(layer "F.Fab")
		)
		(fp_line
			(start -0.67945 -0.305054)
			(end -0.12065 -0.305054)
			(stroke
				(width 0.1)
				(type default)
			)
			(layer "F.Fab")
		)
		(fp_line
			(start -0.12065 -0.305054)
			(end -0.12065 -0.2794)
			(stroke
				(width 0.1)
				(type default)
			)
			(layer "F.Fab")
		)
		(pad "1" smd circle
			(at -0.40005 0 270)
			(size 0 0)
			(layers "F.Cu" "F.Mask" "F.Paste")
			(net "P3V3_NIC0")
		)
		(pad "2" smd circle
			(at 0.40005 0 270)
			(size 0 0)
			(layers "F.Cu" "F.Mask" "F.Paste")
			(net "GND")
		)
	)
	(footprint ""
		(layer "F.Cu")
		(at 107.518454 -120.53824 180)
		(property "Reference" "R5861"
			(at 0 0 180)
			(layer "F.SilkS")
			(hide yes)
			(effects
				(font
					(size 1.27 1.27)
				)
			)
		)
		(property "Value" ""
			(at 0 0 180)
			(layer "F.Fab")
			(effects
				(font
					(size 1.27 1.27)
				)
			)
		)
		(duplicate_pad_numbers_are_jumpers no)
		(fp_line
			(start 0.7874 0.4064)
			(end -0.7874 0.4064)
			(stroke
				(width 0.1524)
				(type default)
			)
			(layer "F.SilkS")
		)
		(fp_line
			(start 0.7874 -0.4064)
			(end 0.7874 0.4064)
			(stroke
				(width 0.1524)
				(type default)
			)
			(layer "F.SilkS")
		)
		(fp_line
			(start -0.7874 0.4064)
			(end -0.7874 -0.4064)
			(stroke
				(width 0.1524)
				(type default)
			)
			(layer "F.SilkS")
		)
		(fp_line
			(start -0.7874 -0.4064)
			(end 0.7874 -0.4064)
			(stroke
				(width 0.1524)
				(type default)
			)
			(layer "F.SilkS")
		)
		(fp_line
			(start 0.67945 0.3048)
			(end 0.120396 0.3048)
			(stroke
				(width 0.1)
				(type default)
			)
			(layer "F.Fab")
		)
		(fp_line
			(start 0.67945 -0.3048)
			(end 0.67945 0.3048)
			(stroke
				(width 0.1)
				(type default)
			)
			(layer "F.Fab")
		)
		(fp_line
			(start 0.12065 -0.2794)
			(end 0.12065 -0.3048)
			(stroke
				(width 0.1)
				(type default)
			)
			(layer "F.Fab")
		)
		(fp_line
			(start 0.12065 -0.3048)
			(end 0.67945 -0.3048)
			(stroke
				(width 0.1)
				(type default)
			)
			(layer "F.Fab")
		)
		(fp_line
			(start 0.120396 0.3048)
			(end 0.120396 0.2794)
			(stroke
				(width 0.1)
				(type default)
			)
			(layer "F.Fab")
		)
		(fp_line
			(start 0.120396 0.2794)
			(end -0.12065 0.2794)
			(stroke
				(width 0.1)
				(type default)
			)
			(layer "F.Fab")
		)
		(fp_line
			(start -0.12065 0.3048)
			(end -0.67945 0.3048)
			(stroke
				(width 0.1)
				(type default)
			)
			(layer "F.Fab")
		)
		(fp_line
			(start -0.12065 0.2794)
			(end -0.12065 0.3048)
			(stroke
				(width 0.1)
				(type default)
			)
			(layer "F.Fab")
		)
		(fp_line
			(start -0.12065 -0.2794)
			(end 0.12065 -0.2794)
			(stroke
				(width 0.1)
				(type default)
			)
			(layer "F.Fab")
		)
		(fp_line
			(start -0.12065 -0.305054)
			(end -0.12065 -0.2794)
			(stroke
				(width 0.1)
				(type default)
			)
			(layer "F.Fab")
		)
		(fp_line
			(start -0.67945 0.3048)
			(end -0.67945 -0.305054)
			(stroke
				(width 0.1)
				(type default)
			)
			(layer "F.Fab")
		)
		(fp_line
			(start -0.67945 -0.305054)
			(end -0.12065 -0.305054)
			(stroke
				(width 0.1)
				(type default)
			)
			(layer "F.Fab")
		)
		(pad "1" smd circle
			(at -0.40005 0 180)
			(size 0 0)
			(layers "F.Cu" "F.Mask" "F.Paste")
			(net "P5V_AUX")
		)
		(pad "2" smd circle
			(at 0.40005 0 180)
			(size 0 0)
			(layers "F.Cu" "F.Mask" "F.Paste")
			(net "P3V3_NIC1_PG_G2")
		)
	)
	(footprint ""
		(layer "F.Cu")
		(at 172.081444 -157.8356)
		(property "Reference" "R150"
			(at 0 0 0)
			(layer "F.SilkS")
			(hide yes)
			(effects
				(font
					(size 1.27 1.27)
				)
			)
		)
		(property "Value" ""
			(at 0 0 0)
			(layer "F.Fab")
			(effects
				(font
					(size 1.27 1.27)
				)
			)
		)
		(duplicate_pad_numbers_are_jumpers no)
		(fp_line
			(start -0.7874 -0.4064)
			(end 0.7874 -0.4064)
			(stroke
				(width 0.1524)
				(type default)
			)
			(layer "F.SilkS")
		)
		(fp_line
			(start -0.7874 0.4064)
			(end -0.7874 -0.4064)
			(stroke
				(width 0.1524)
				(type default)
			)
			(layer "F.SilkS")
		)
		(fp_line
			(start 0.7874 -0.4064)
			(end 0.7874 0.4064)
			(stroke
				(width 0.1524)
				(type default)
			)
			(layer "F.SilkS")
		)
		(fp_line
			(start 0.7874 0.4064)
			(end -0.7874 0.4064)
			(stroke
				(width 0.1524)
				(type default)
			)
			(layer "F.SilkS")
		)
		(fp_line
			(start -0.67945 -0.305054)
			(end -0.12065 -0.305054)
			(stroke
				(width 0.1)
				(type default)
			)
			(layer "F.Fab")
		)
		(fp_line
			(start -0.67945 0.3048)
			(end -0.67945 -0.305054)
			(stroke
				(width 0.1)
				(type default)
			)
			(layer "F.Fab")
		)
		(fp_line
			(start -0.12065 -0.305054)
			(end -0.12065 -0.2794)
			(stroke
				(width 0.1)
				(type default)
			)
			(layer "F.Fab")
		)
		(fp_line
			(start -0.12065 -0.2794)
			(end 0.12065 -0.2794)
			(stroke
				(width 0.1)
				(type default)
			)
			(layer "F.Fab")
		)
		(fp_line
			(start -0.12065 0.2794)
			(end -0.12065 0.3048)
			(stroke
				(width 0.1)
				(type default)
			)
			(layer "F.Fab")
		)
		(fp_line
			(start -0.12065 0.3048)
			(end -0.67945 0.3048)
			(stroke
				(width 0.1)
				(type default)
			)
			(layer "F.Fab")
		)
		(fp_line
			(start 0.120396 0.2794)
			(end -0.12065 0.2794)
			(stroke
				(width 0.1)
				(type default)
			)
			(layer "F.Fab")
		)
		(fp_line
			(start 0.120396 0.3048)
			(end 0.120396 0.2794)
			(stroke
				(width 0.1)
				(type default)
			)
			(layer "F.Fab")
		)
		(fp_line
			(start 0.12065 -0.3048)
			(end 0.67945 -0.3048)
			(stroke
				(width 0.1)
				(type default)
			)
			(layer "F.Fab")
		)
		(fp_line
			(start 0.12065 -0.2794)
			(end 0.12065 -0.3048)
			(stroke
				(width 0.1)
				(type default)
			)
			(layer "F.Fab")
		)
		(fp_line
			(start 0.67945 -0.3048)
			(end 0.67945 0.3048)
			(stroke
				(width 0.1)
				(type default)
			)
			(layer "F.Fab")
		)
		(fp_line
			(start 0.67945 0.3048)
			(end 0.120396 0.3048)
			(stroke
				(width 0.1)
				(type default)
			)
			(layer "F.Fab")
		)
		(pad "1" smd circle
			(at -0.40005 0)
			(size 0 0)
			(layers "F.Cu" "F.Mask" "F.Paste")
			(net "RST_NIC2_PERST3_R_N")
		)
		(pad "2" smd circle
			(at 0.40005 0)
			(size 0 0)
			(layers "F.Cu" "F.Mask" "F.Paste")
			(net "RST_HP_NIC2_BUF_N")
		)
	)
	(footprint ""
		(layer "F.Cu")
		(at 460.19974 -288.140648)
		(property "Reference" "PC276"
			(at 0 0 0)
			(layer "F.SilkS")
			(hide yes)
			(effects
				(font
					(size 1.27 1.27)
				)
			)
		)
		(property "Value" ""
			(at 0 0 0)
			(layer "F.Fab")
			(effects
				(font
					(size 1.27 1.27)
				)
			)
		)
		(duplicate_pad_numbers_are_jumpers no)
		(fp_line
			(start -0.7874 -0.4064)
			(end 0.7874 -0.4064)
			(stroke
				(width 0.1524)
				(type default)
			)
			(layer "F.SilkS")
		)
		(fp_line
			(start -0.7874 0.4064)
			(end -0.7874 -0.4064)
			(stroke
				(width 0.1524)
				(type default)
			)
			(layer "F.SilkS")
		)
		(fp_line
			(start 0.7874 -0.4064)
			(end 0.7874 0.4064)
			(stroke
				(width 0.1524)
				(type default)
			)
			(layer "F.SilkS")
		)
		(fp_line
			(start 0.7874 0.4064)
			(end -0.7874 0.4064)
			(stroke
				(width 0.1524)
				(type default)
			)
			(layer "F.SilkS")
		)
		(fp_line
			(start -0.67945 -0.305054)
			(end -0.12065 -0.305054)
			(stroke
				(width 0.1)
				(type default)
			)
			(layer "F.Fab")
		)
		(fp_line
			(start -0.67945 0.3048)
			(end -0.67945 -0.305054)
			(stroke
				(width 0.1)
				(type default)
			)
			(layer "F.Fab")
		)
		(fp_line
			(start -0.12065 -0.305054)
			(end -0.12065 -0.2794)
			(stroke
				(width 0.1)
				(type default)
			)
			(layer "F.Fab")
		)
		(fp_line
			(start -0.12065 -0.2794)
			(end 0.12065 -0.2794)
			(stroke
				(width 0.1)
				(type default)
			)
			(layer "F.Fab")
		)
		(fp_line
			(start -0.12065 0.2794)
			(end -0.12065 0.3048)
			(stroke
				(width 0.1)
				(type default)
			)
			(layer "F.Fab")
		)
		(fp_line
			(start -0.12065 0.3048)
			(end -0.67945 0.3048)
			(stroke
				(width 0.1)
				(type default)
			)
			(layer "F.Fab")
		)
		(fp_line
			(start 0.120396 0.2794)
			(end -0.12065 0.2794)
			(stroke
				(width 0.1)
				(type default)
			)
			(layer "F.Fab")
		)
		(fp_line
			(start 0.120396 0.3048)
			(end 0.120396 0.2794)
			(stroke
				(width 0.1)
				(type default)
			)
			(layer "F.Fab")
		)
		(fp_line
			(start 0.12065 -0.3048)
			(end 0.67945 -0.3048)
			(stroke
				(width 0.1)
				(type default)
			)
			(layer "F.Fab")
		)
		(fp_line
			(start 0.12065 -0.2794)
			(end 0.12065 -0.3048)
			(stroke
				(width 0.1)
				(type default)
			)
			(layer "F.Fab")
		)
		(fp_line
			(start 0.67945 -0.3048)
			(end 0.67945 0.3048)
			(stroke
				(width 0.1)
				(type default)
			)
			(layer "F.Fab")
		)
		(fp_line
			(start 0.67945 0.3048)
			(end 0.120396 0.3048)
			(stroke
				(width 0.1)
				(type default)
			)
			(layer "F.Fab")
		)
		(pad "1" smd circle
			(at -0.40005 0)
			(size 0 0)
			(layers "F.Cu" "F.Mask" "F.Paste")
			(net "P1V25_PEX3_R")
		)
		(pad "2" smd circle
			(at 0.40005 0)
			(size 0 0)
			(layers "F.Cu" "F.Mask" "F.Paste")
			(net "GND")
		)
	)
)
